(kicad_pcb
	(version 20260206)
	(generator "pcbnew")
	(generator_version "10.0")
	(general
		(thickness 1.6)
		(legacy_teardrops no)
	)
	(paper "A4")
	(title_block
		(title "03242023_DA0F0TMBIJ0_F0T_Motherboard_J_brd_V01_OCP.brd")
		(comment 1 "Grand Teton / footprints 6018-6023 of 6105")
	)
	(layers
		(0 "F.Cu" signal "TOP")
		(4 "In1.Cu" signal "GND")
		(6 "In2.Cu" signal "IN1")
		(8 "In3.Cu" signal "GND1")
		(10 "In4.Cu" signal "IN2")
		(12 "In5.Cu" signal "GND2")
		(14 "In6.Cu" signal "IN3")
		(16 "In7.Cu" signal "GND3")
		(18 "In8.Cu" signal "VCC")
		(20 "In9.Cu" signal "VCC1")
		(22 "In10.Cu" signal "GND4")
		(24 "In11.Cu" signal "IN4")
		(26 "In12.Cu" signal "GND5")
		(28 "In13.Cu" signal "IN5")
		(30 "In14.Cu" signal "GND6")
		(32 "In15.Cu" signal "IN6")
		(34 "In16.Cu" signal "GND7")
		(2 "B.Cu" signal "BOTTOM")
		(9 "F.Adhes" user "F.Adhesive")
		(11 "B.Adhes" user "B.Adhesive")
		(13 "F.Paste" user "Package Geometry/Pastemask Top")
		(15 "B.Paste" user "Package Geometry/Pastemask Bottom")
		(5 "F.SilkS" user "Ref Des/Silkscreen Top")
		(7 "B.SilkS" user "Ref Des/Silkscreen Bottom")
		(1 "F.Mask" user "Board Geometry/Soldermask Top")
		(3 "B.Mask" user "Board Geometry/Soldermask Bottom")
		(17 "Dwgs.User" user "User.Drawings")
		(19 "Cmts.User" user "User.Comments")
		(21 "Eco1.User" user "User.Eco1")
		(23 "Eco2.User" user "User.Eco2")
		(25 "Edge.Cuts" user "Board Geometry/Outline")
		(27 "Margin" user)
		(31 "F.CrtYd" user "Package Geometry/Place Bound Top")
		(29 "B.CrtYd" user "Package Geometry/Place Bound Bottom")
		(35 "F.Fab" user "Ref Des/Assembly Top")
		(33 "B.Fab" user "Ref Des/Assembly Bottom")
	)
	(footprint ""
		(layer "B.Cu")
		(at 71.385684 -185.791856 90)
		(property "Reference" "R560"
			(at 0 0 90)
			(layer "B.SilkS")
			(hide yes)
			(effects
				(font
					(size 1.27 1.27)
				)
				(justify mirror)
			)
		)
		(property "Value" ""
			(at 0 0 90)
			(layer "B.Fab")
			(effects
				(font
					(size 1.27 1.27)
				)
				(justify mirror)
			)
		)
		(duplicate_pad_numbers_are_jumpers no)
		(fp_line
			(start 0.7874 -0.4064)
			(end -0.7874 -0.4064)
			(stroke
				(width 0.1524)
				(type default)
			)
			(layer "B.SilkS")
		)
		(fp_line
			(start -0.7874 -0.4064)
			(end -0.7874 0.4064)
			(stroke
				(width 0.1524)
				(type default)
			)
			(layer "B.SilkS")
		)
		(fp_line
			(start 0.7874 0.4064)
			(end 0.7874 -0.4064)
			(stroke
				(width 0.1524)
				(type default)
			)
			(layer "B.SilkS")
		)
		(fp_line
			(start -0.7874 0.4064)
			(end 0.7874 0.4064)
			(stroke
				(width 0.1524)
				(type default)
			)
			(layer "B.SilkS")
		)
		(fp_line
			(start 0.67945 -0.305054)
			(end 0.12065 -0.305054)
			(stroke
				(width 0.1)
				(type default)
			)
			(layer "B.Fab")
		)
		(fp_line
			(start 0.12065 -0.305054)
			(end 0.12065 -0.2794)
			(stroke
				(width 0.1)
				(type default)
			)
			(layer "B.Fab")
		)
		(fp_line
			(start -0.12065 -0.3048)
			(end -0.67945 -0.3048)
			(stroke
				(width 0.1)
				(type default)
			)
			(layer "B.Fab")
		)
		(fp_line
			(start -0.67945 -0.3048)
			(end -0.67945 0.3048)
			(stroke
				(width 0.1)
				(type default)
			)
			(layer "B.Fab")
		)
		(fp_line
			(start 0.12065 -0.2794)
			(end -0.12065 -0.2794)
			(stroke
				(width 0.1)
				(type default)
			)
			(layer "B.Fab")
		)
		(fp_line
			(start -0.12065 -0.2794)
			(end -0.12065 -0.3048)
			(stroke
				(width 0.1)
				(type default)
			)
			(layer "B.Fab")
		)
		(fp_line
			(start 0.12065 0.2794)
			(end 0.12065 0.3048)
			(stroke
				(width 0.1)
				(type default)
			)
			(layer "B.Fab")
		)
		(fp_line
			(start -0.120396 0.2794)
			(end 0.12065 0.2794)
			(stroke
				(width 0.1)
				(type default)
			)
			(layer "B.Fab")
		)
		(fp_line
			(start 0.67945 0.3048)
			(end 0.67945 -0.305054)
			(stroke
				(width 0.1)
				(type default)
			)
			(layer "B.Fab")
		)
		(fp_line
			(start 0.12065 0.3048)
			(end 0.67945 0.3048)
			(stroke
				(width 0.1)
				(type default)
			)
			(layer "B.Fab")
		)
		(fp_line
			(start -0.120396 0.3048)
			(end -0.120396 0.2794)
			(stroke
				(width 0.1)
				(type default)
			)
			(layer "B.Fab")
		)
		(fp_line
			(start -0.67945 0.3048)
			(end -0.120396 0.3048)
			(stroke
				(width 0.1)
				(type default)
			)
			(layer "B.Fab")
		)
		(pad "1" smd circle
			(at 0.40005 0 270)
			(size 0 0)
			(layers "B.Cu" "B.Mask" "B.Paste")
			(net "SVID_ALERT1_CPU1_R_N")
		)
		(pad "2" smd circle
			(at -0.40005 0 270)
			(size 0 0)
			(layers "B.Cu" "B.Mask" "B.Paste")
			(net "PVNN_TERM_CPU1")
		)
	)
	(footprint ""
		(layer "B.Cu")
		(at 17.596358 -318.666622)
		(property "Reference" "R80"
			(at 0 0 0)
			(layer "B.SilkS")
			(hide yes)
			(effects
				(font
					(size 1.27 1.27)
				)
				(justify mirror)
			)
		)
		(property "Value" ""
			(at 0 0 0)
			(layer "B.Fab")
			(effects
				(font
					(size 1.27 1.27)
				)
				(justify mirror)
			)
		)
		(duplicate_pad_numbers_are_jumpers no)
		(fp_line
			(start -0.7874 -0.4064)
			(end -0.7874 0.4064)
			(stroke
				(width 0.1524)
				(type default)
			)
			(layer "B.SilkS")
		)
		(fp_line
			(start -0.7874 0.4064)
			(end 0.7874 0.4064)
			(stroke
				(width 0.1524)
				(type default)
			)
			(layer "B.SilkS")
		)
		(fp_line
			(start 0.7874 -0.4064)
			(end -0.7874 -0.4064)
			(stroke
				(width 0.1524)
				(type default)
			)
			(layer "B.SilkS")
		)
		(fp_line
			(start 0.7874 0.4064)
			(end 0.7874 -0.4064)
			(stroke
				(width 0.1524)
				(type default)
			)
			(layer "B.SilkS")
		)
		(fp_line
			(start -0.67945 -0.3048)
			(end -0.67945 0.3048)
			(stroke
				(width 0.1)
				(type default)
			)
			(layer "B.Fab")
		)
		(fp_line
			(start -0.67945 0.3048)
			(end -0.120396 0.3048)
			(stroke
				(width 0.1)
				(type default)
			)
			(layer "B.Fab")
		)
		(fp_line
			(start -0.12065 -0.3048)
			(end -0.67945 -0.3048)
			(stroke
				(width 0.1)
				(type default)
			)
			(layer "B.Fab")
		)
		(fp_line
			(start -0.12065 -0.2794)
			(end -0.12065 -0.3048)
			(stroke
				(width 0.1)
				(type default)
			)
			(layer "B.Fab")
		)
		(fp_line
			(start -0.120396 0.2794)
			(end 0.12065 0.2794)
			(stroke
				(width 0.1)
				(type default)
			)
			(layer "B.Fab")
		)
		(fp_line
			(start -0.120396 0.3048)
			(end -0.120396 0.2794)
			(stroke
				(width 0.1)
				(type default)
			)
			(layer "B.Fab")
		)
		(fp_line
			(start 0.12065 -0.305054)
			(end 0.12065 -0.2794)
			(stroke
				(width 0.1)
				(type default)
			)
			(layer "B.Fab")
		)
		(fp_line
			(start 0.12065 -0.2794)
			(end -0.12065 -0.2794)
			(stroke
				(width 0.1)
				(type default)
			)
			(layer "B.Fab")
		)
		(fp_line
			(start 0.12065 0.2794)
			(end 0.12065 0.3048)
			(stroke
				(width 0.1)
				(type default)
			)
			(layer "B.Fab")
		)
		(fp_line
			(start 0.12065 0.3048)
			(end 0.67945 0.3048)
			(stroke
				(width 0.1)
				(type default)
			)
			(layer "B.Fab")
		)
		(fp_line
			(start 0.67945 -0.305054)
			(end 0.12065 -0.305054)
			(stroke
				(width 0.1)
				(type default)
			)
			(layer "B.Fab")
		)
		(fp_line
			(start 0.67945 0.3048)
			(end 0.67945 -0.305054)
			(stroke
				(width 0.1)
				(type default)
			)
			(layer "B.Fab")
		)
		(pad "1" smd circle
			(at 0.40005 0 180)
			(size 0 0)
			(layers "B.Cu" "B.Mask" "B.Paste")
			(net "PD_CHD_CPU1_DIMM2_SAA")
		)
		(pad "2" smd circle
			(at -0.40005 0 180)
			(size 0 0)
			(layers "B.Cu" "B.Mask" "B.Paste")
			(net "GND")
		)
	)
	(footprint ""
		(layer "B.Cu")
		(at 170.555666 -109.775498)
		(property "Reference" "C1901"
			(at 0 0 0)
			(layer "B.SilkS")
			(hide yes)
			(effects
				(font
					(size 1.27 1.27)
				)
				(justify mirror)
			)
		)
		(property "Value" ""
			(at 0 0 0)
			(layer "B.Fab")
			(effects
				(font
					(size 1.27 1.27)
				)
				(justify mirror)
			)
		)
		(duplicate_pad_numbers_are_jumpers no)
		(fp_line
			(start -0.69215 -0.2921)
			(end -0.69215 0.2921)
			(stroke
				(width 0.1524)
				(type default)
			)
			(layer "B.SilkS")
		)
		(fp_line
			(start -0.69215 0.2921)
			(end 0.69215 0.2921)
			(stroke
				(width 0.1524)
				(type default)
			)
			(layer "B.SilkS")
		)
		(fp_line
			(start 0.69215 -0.2921)
			(end -0.69215 -0.2921)
			(stroke
				(width 0.1524)
				(type default)
			)
			(layer "B.SilkS")
		)
		(fp_line
			(start 0.69215 0.2921)
			(end 0.69215 -0.2921)
			(stroke
				(width 0.1524)
				(type default)
			)
			(layer "B.SilkS")
		)
		(fp_line
			(start -0.51435 -0.2794)
			(end -0.51435 0.2794)
			(stroke
				(width 0.1)
				(type default)
			)
			(layer "B.Fab")
		)
		(fp_line
			(start -0.51435 0.2794)
			(end 0.51435 0.2794)
			(stroke
				(width 0.1)
				(type default)
			)
			(layer "B.Fab")
		)
		(fp_line
			(start 0.51435 -0.2794)
			(end -0.51435 -0.2794)
			(stroke
				(width 0.1)
				(type default)
			)
			(layer "B.Fab")
		)
		(fp_line
			(start 0.51435 0.2794)
			(end 0.51435 -0.2794)
			(stroke
				(width 0.1)
				(type default)
			)
			(layer "B.Fab")
		)
		(pad "1" smd circle
			(at 0.40005 0 180)
			(size 0 0)
			(layers "B.Cu" "B.Mask" "B.Paste")
			(net "P3V3_AUX_FPGA_VCCIO0")
		)
		(pad "2" smd circle
			(at -0.40005 0 180)
			(size 0 0)
			(layers "B.Cu" "B.Mask" "B.Paste")
			(net "GND")
		)
		(zone
			(layer "B.Cu")
			(hatch none 0.5)
			(connect_pads
				(clearance 0)
			)
			(min_thickness 0.25)
			(keepout
				(tracks not_allowed)
				(vias allowed)
				(pads allowed)
				(copperpour not_allowed)
				(footprints allowed)
			)
			(placement
				(enabled no)
				(sheetname "")
			)
			(fill
				(thermal_gap 0.5)
				(thermal_bridge_width 0.5)
				(island_removal_mode 0)
			)
			(polygon
				(pts
					(xy 170.746166 -109.687868) (xy 170.654726 -109.629702) (xy 170.455336 -109.629702) (xy 170.365166 -109.687868)
					(xy 170.365166 -109.863128) (xy 170.455336 -109.921548) (xy 170.654726 -109.921548) (xy 170.746166 -109.863382)
				)
			)
		)
	)
	(footprint ""
		(layer "B.Cu")
		(at 22.989032 -172.181774 180)
		(property "Reference" "R2582"
			(at 0 0 0)
			(layer "B.SilkS")
			(hide yes)
			(effects
				(font
					(size 1.27 1.27)
				)
				(justify mirror)
			)
		)
		(property "Value" ""
			(at 0 0 0)
			(layer "B.Fab")
			(effects
				(font
					(size 1.27 1.27)
				)
				(justify mirror)
			)
		)
		(duplicate_pad_numbers_are_jumpers no)
		(fp_line
			(start 0.7874 0.4064)
			(end 0.7874 -0.4064)
			(stroke
				(width 0.1524)
				(type default)
			)
			(layer "B.SilkS")
		)
		(fp_line
			(start 0.7874 -0.4064)
			(end -0.7874 -0.4064)
			(stroke
				(width 0.1524)
				(type default)
			)
			(layer "B.SilkS")
		)
		(fp_line
			(start -0.7874 0.4064)
			(end 0.7874 0.4064)
			(stroke
				(width 0.1524)
				(type default)
			)
			(layer "B.SilkS")
		)
		(fp_line
			(start -0.7874 -0.4064)
			(end -0.7874 0.4064)
			(stroke
				(width 0.1524)
				(type default)
			)
			(layer "B.SilkS")
		)
		(fp_line
			(start 0.67945 0.3048)
			(end 0.67945 -0.305054)
			(stroke
				(width 0.1)
				(type default)
			)
			(layer "B.Fab")
		)
		(fp_line
			(start 0.67945 -0.305054)
			(end 0.12065 -0.305054)
			(stroke
				(width 0.1)
				(type default)
			)
			(layer "B.Fab")
		)
		(fp_line
			(start 0.12065 0.3048)
			(end 0.67945 0.3048)
			(stroke
				(width 0.1)
				(type default)
			)
			(layer "B.Fab")
		)
		(fp_line
			(start 0.12065 0.2794)
			(end 0.12065 0.3048)
			(stroke
				(width 0.1)
				(type default)
			)
			(layer "B.Fab")
		)
		(fp_line
			(start 0.12065 -0.2794)
			(end -0.12065 -0.2794)
			(stroke
				(width 0.1)
				(type default)
			)
			(layer "B.Fab")
		)
		(fp_line
			(start 0.12065 -0.305054)
			(end 0.12065 -0.2794)
			(stroke
				(width 0.1)
				(type default)
			)
			(layer "B.Fab")
		)
		(fp_line
			(start -0.120396 0.3048)
			(end -0.120396 0.2794)
			(stroke
				(width 0.1)
				(type default)
			)
			(layer "B.Fab")
		)
		(fp_line
			(start -0.120396 0.2794)
			(end 0.12065 0.2794)
			(stroke
				(width 0.1)
				(type default)
			)
			(layer "B.Fab")
		)
		(fp_line
			(start -0.12065 -0.2794)
			(end -0.12065 -0.3048)
			(stroke
				(width 0.1)
				(type default)
			)
			(layer "B.Fab")
		)
		(fp_line
			(start -0.12065 -0.3048)
			(end -0.67945 -0.3048)
			(stroke
				(width 0.1)
				(type default)
			)
			(layer "B.Fab")
		)
		(fp_line
			(start -0.67945 0.3048)
			(end -0.120396 0.3048)
			(stroke
				(width 0.1)
				(type default)
			)
			(layer "B.Fab")
		)
		(fp_line
			(start -0.67945 -0.3048)
			(end -0.67945 0.3048)
			(stroke
				(width 0.1)
				(type default)
			)
			(layer "B.Fab")
		)
		(pad "1" smd circle
			(at 0.40005 0)
			(size 0 0)
			(layers "B.Cu" "B.Mask" "B.Paste")
			(net "SMB_VR_3V3AUX_SDA_R")
		)
		(pad "2" smd circle
			(at -0.40005 0)
			(size 0 0)
			(layers "B.Cu" "B.Mask" "B.Paste")
			(net "SMB_DIO_PVCCD_HV_CPU1")
		)
	)
	(footprint ""
		(layer "B.Cu")
		(at 208.30794 -316.258448 90)
		(property "Reference" "R3905"
			(at 0 0 90)
			(layer "B.SilkS")
			(hide yes)
			(effects
				(font
					(size 1.27 1.27)
				)
				(justify mirror)
			)
		)
		(property "Value" ""
			(at 0 0 90)
			(layer "B.Fab")
			(effects
				(font
					(size 1.27 1.27)
				)
				(justify mirror)
			)
		)
		(duplicate_pad_numbers_are_jumpers no)
		(fp_line
			(start 0.7874 -0.4064)
			(end -0.7874 -0.4064)
			(stroke
				(width 0.1524)
				(type default)
			)
			(layer "B.SilkS")
		)
		(fp_line
			(start -0.7874 -0.4064)
			(end -0.7874 0.4064)
			(stroke
				(width 0.1524)
				(type default)
			)
			(layer "B.SilkS")
		)
		(fp_line
			(start 0.7874 0.4064)
			(end 0.7874 -0.4064)
			(stroke
				(width 0.1524)
				(type default)
			)
			(layer "B.SilkS")
		)
		(fp_line
			(start -0.7874 0.4064)
			(end 0.7874 0.4064)
			(stroke
				(width 0.1524)
				(type default)
			)
			(layer "B.SilkS")
		)
		(fp_line
			(start 0.67945 -0.305054)
			(end 0.12065 -0.305054)
			(stroke
				(width 0.1)
				(type default)
			)
			(layer "B.Fab")
		)
		(fp_line
			(start 0.12065 -0.305054)
			(end 0.12065 -0.2794)
			(stroke
				(width 0.1)
				(type default)
			)
			(layer "B.Fab")
		)
		(fp_line
			(start -0.12065 -0.3048)
			(end -0.67945 -0.3048)
			(stroke
				(width 0.1)
				(type default)
			)
			(layer "B.Fab")
		)
		(fp_line
			(start -0.67945 -0.3048)
			(end -0.67945 0.3048)
			(stroke
				(width 0.1)
				(type default)
			)
			(layer "B.Fab")
		)
		(fp_line
			(start 0.12065 -0.2794)
			(end -0.12065 -0.2794)
			(stroke
				(width 0.1)
				(type default)
			)
			(layer "B.Fab")
		)
		(fp_line
			(start -0.12065 -0.2794)
			(end -0.12065 -0.3048)
			(stroke
				(width 0.1)
				(type default)
			)
			(layer "B.Fab")
		)
		(fp_line
			(start 0.12065 0.2794)
			(end 0.12065 0.3048)
			(stroke
				(width 0.1)
				(type default)
			)
			(layer "B.Fab")
		)
		(fp_line
			(start -0.120396 0.2794)
			(end 0.12065 0.2794)
			(stroke
				(width 0.1)
				(type default)
			)
			(layer "B.Fab")
		)
		(fp_line
			(start 0.67945 0.3048)
			(end 0.67945 -0.305054)
			(stroke
				(width 0.1)
				(type default)
			)
			(layer "B.Fab")
		)
		(fp_line
			(start 0.12065 0.3048)
			(end 0.67945 0.3048)
			(stroke
				(width 0.1)
				(type default)
			)
			(layer "B.Fab")
		)
		(fp_line
			(start -0.120396 0.3048)
			(end -0.120396 0.2794)
			(stroke
				(width 0.1)
				(type default)
			)
			(layer "B.Fab")
		)
		(fp_line
			(start -0.67945 0.3048)
			(end -0.120396 0.3048)
			(stroke
				(width 0.1)
				(type default)
			)
			(layer "B.Fab")
		)
		(pad "1" smd circle
			(at 0.40005 0 270)
			(size 0 0)
			(layers "B.Cu" "B.Mask" "B.Paste")
			(net "I3C_SPD_DDREFGH_CPU1_LVC1_SCL_6")
		)
		(pad "2" smd circle
			(at -0.40005 0 270)
			(size 0 0)
			(layers "B.Cu" "B.Mask" "B.Paste")
			(net "I3C_SPD_DDREFGH_CPU1_LVC1_SCL")
		)
	)
	(footprint ""
		(layer "B.Cu")
		(at 61.462412 -177.636678)
		(property "Reference" "PC435"
			(at 0 0 0)
			(layer "B.SilkS")
			(hide yes)
			(effects
				(font
					(size 1.27 1.27)
				)
				(justify mirror)
			)
		)
		(property "Value" ""
			(at 0 0 0)
			(layer "B.Fab")
			(effects
				(font
					(size 1.27 1.27)
				)
				(justify mirror)
			)
		)
		(duplicate_pad_numbers_are_jumpers no)
		(fp_line
			(start -1.524 -0.762)
			(end -1.524 0.762)
			(stroke
				(width 0.1524)
				(type default)
			)
			(layer "B.SilkS")
		)
		(fp_line
			(start -1.524 0.762)
			(end 1.524 0.762)
			(stroke
				(width 0.1524)
				(type default)
			)
			(layer "B.SilkS")
		)
		(fp_line
			(start 1.524 -0.762)
			(end -1.524 -0.762)
			(stroke
				(width 0.1524)
				(type default)
			)
			(layer "B.SilkS")
		)
		(fp_line
			(start 1.524 0.762)
			(end 1.524 -0.762)
			(stroke
				(width 0.1524)
				(type default)
			)
			(layer "B.SilkS")
		)
		(fp_line
			(start -1.1049 -0.724916)
			(end 1.1049 -0.724916)
			(stroke
				(width 0.1)
				(type default)
			)
			(layer "B.Fab")
		)
		(fp_line
			(start -1.1049 0.724916)
			(end -1.1049 -0.724916)
			(stroke
				(width 0.1)
				(type default)
			)
			(layer "B.Fab")
		)
		(fp_line
			(start 1.1049 -0.724916)
			(end 1.1049 0.724916)
			(stroke
				(width 0.1)
				(type default)
			)
			(layer "B.Fab")
		)
		(fp_line
			(start 1.1049 0.724916)
			(end -1.1049 0.724916)
			(stroke
				(width 0.1)
				(type default)
			)
			(layer "B.Fab")
		)
		(pad "1" smd rect
			(at 0.889 0)
			(size 1.016 1.27)
			(layers "B.Cu" "B.Mask" "B.Paste")
			(net "PVCCFA_EHV_CPU1")
		)
		(pad "2" smd rect
			(at -0.889 0)
			(size 1.016 1.27)
			(layers "B.Cu" "B.Mask" "B.Paste")
			(net "GND")
		)
	)
)
